(kicad_pcb
	(version 20241229)
	(generator "pcbnew")
	(generator_version "9.0")
	(general
		(thickness 1.6642)
		(legacy_teardrops no)
	)
	(paper "A3")
	(title_block
		(title "PolarFire SoM")
		(date "2025-07-22")
		(rev "1.1.4")
		(company "Antmicro Ltd")
		(comment 1 "www.antmicro.com")
		(comment 9 "footprints 408-411 of 470")
	)
	(layers
		(0 "F.Cu" mixed)
		(4 "In1.Cu" power)
		(6 "In2.Cu" signal)
		(8 "In3.Cu" power)
		(10 "In4.Cu" signal)
		(12 "In5.Cu" power)
		(14 "In6.Cu" power)
		(16 "In7.Cu" signal)
		(18 "In8.Cu" power)
		(20 "In9.Cu" signal)
		(22 "In10.Cu" power)
		(24 "In11.Cu" signal)
		(26 "In12.Cu" signal)
		(2 "B.Cu" mixed)
		(9 "F.Adhes" user "F.Adhesive")
		(11 "B.Adhes" user "B.Adhesive")
		(13 "F.Paste" user)
		(15 "B.Paste" user)
		(5 "F.SilkS" user "F.Silkscreen")
		(7 "B.SilkS" user "B.Silkscreen")
		(1 "F.Mask" user)
		(3 "B.Mask" user)
		(17 "Dwgs.User" user "User.Drawings")
		(19 "Cmts.User" user "User.Comments")
		(21 "Eco1.User" user "User.Eco1")
		(23 "Eco2.User" user "User.Eco2")
		(25 "Edge.Cuts" user)
		(27 "Margin" user)
		(31 "F.CrtYd" user "F.Courtyard")
		(29 "B.CrtYd" user "B.Courtyard")
		(35 "F.Fab" user)
		(33 "B.Fab" user)
	)
	(footprint "antmicro-footprints:C_0402_1005Metric"
		(layer "B.Cu")
		(at 213.6925 131.197 90)
		(descr "Capacitor SMD 0402")
		(tags "capacitor SMD 0402")
		(property "Reference" "C72"
			(at 0.737 0.5075 90)
			(layer "B.SilkS")
			(effects
				(font
					(size 0.7 0.7)
					(thickness 0.15)
				)
				(justify right bottom mirror)
			)
		)
		(property "Value" "C_100n_0402"
			(at -1.022927 -2.155213 90)
			(layer "B.Fab")
			(hide yes)
			(effects
				(font
					(size 0.7 0.7)
					(thickness 0.15)
				)
				(justify right bottom mirror)
			)
		)
		(property "Datasheet" "https://www.murata.com/products/productdetail?partno=GRM155R61H104KE14%23"
			(at 0 0 90)
			(layer "F.Fab")
			(hide yes)
			(effects
				(font
					(size 1.27 1.27)
					(thickness 0.15)
				)
			)
		)
		(property "Description" "SMD Multilayer Ceramic Capacitor, 0.1 µF, 50 V, 0402 [1005 Metric], ± 10%, X5R, GRM Series"
			(at 0 0 90)
			(layer "F.Fab")
			(hide yes)
			(effects
				(font
					(size 1.27 1.27)
					(thickness 0.15)
				)
			)
		)
		(property "Author" "Antmicro"
			(at 344.8895 -82.4955 0)
			(layer "B.Fab")
			(hide yes)
			(effects
				(font
					(size 1 1)
					(thickness 0.15)
				)
				(justify mirror)
			)
		)
		(property "Dielectric" "X5R"
			(at 344.8895 -82.4955 0)
			(layer "B.Fab")
			(hide yes)
			(effects
				(font
					(size 1 1)
					(thickness 0.15)
				)
				(justify mirror)
			)
		)
		(property "License" "Apache-2.0"
			(at 344.8895 -82.4955 0)
			(layer "B.Fab")
			(hide yes)
			(effects
				(font
					(size 1 1)
					(thickness 0.15)
				)
				(justify mirror)
			)
		)
		(property "MPN" "GRM155R61H104KE14D"
			(at 344.8895 -82.4955 0)
			(layer "B.Fab")
			(hide yes)
			(effects
				(font
					(size 1 1)
					(thickness 0.15)
				)
				(justify mirror)
			)
		)
		(property "Manufacturer" "Murata"
			(at 344.8895 -82.4955 0)
			(layer "B.Fab")
			(hide yes)
			(effects
				(font
					(size 1 1)
					(thickness 0.15)
				)
				(justify mirror)
			)
		)
		(property "Public" ""
			(at 344.8895 -82.4955 0)
			(layer "B.Fab")
			(hide yes)
			(effects
				(font
					(size 1 1)
					(thickness 0.15)
				)
				(justify mirror)
			)
		)
		(property "Val" "100n"
			(at 344.8895 -82.4955 0)
			(layer "B.Fab")
			(hide yes)
			(effects
				(font
					(size 1 1)
					(thickness 0.15)
				)
				(justify mirror)
			)
		)
		(property "Voltage" "50V"
			(at 344.8895 -82.4955 0)
			(layer "B.Fab")
			(hide yes)
			(effects
				(font
					(size 1 1)
					(thickness 0.15)
				)
				(justify mirror)
			)
		)
		(sheetname "/Memory/")
		(sheetfile "memory.kicad_sch")
		(attr smd)
		(fp_rect
			(start -0.925 0.47)
			(end 0.925 -0.47)
			(stroke
				(width 0.05)
				(type default)
			)
			(fill no)
			(layer "B.CrtYd")
		)
		(fp_line
			(start 0.504 -0.248)
			(end -0.494 -0.248)
			(stroke
				(width 0.15)
				(type solid)
			)
			(layer "B.Fab")
		)
		(fp_line
			(start -0.494 -0.248)
			(end -0.494 0.25)
			(stroke
				(width 0.15)
				(type solid)
			)
			(layer "B.Fab")
		)
		(fp_line
			(start 0.504 0.25)
			(end 0.504 -0.248)
			(stroke
				(width 0.15)
				(type solid)
			)
			(layer "B.Fab")
		)
		(fp_line
			(start -0.494 0.25)
			(end 0.504 0.25)
			(stroke
				(width 0.15)
				(type solid)
			)
			(layer "B.Fab")
		)
		(fp_text user "Author: Antmicro"
			(at -0.939 -3.399 270)
			(layer "B.Fab")
			(effects
				(font
					(size 0.7 0.7)
					(thickness 0.15)
				)
				(justify left bottom mirror)
			)
		)
		(fp_text user "License: Apache-2.0"
			(at -0.939 -5.799 270)
			(layer "B.Fab")
			(effects
				(font
					(size 0.7 0.7)
					(thickness 0.15)
				)
				(justify left bottom mirror)
			)
		)
		(fp_text user "${REFERENCE}"
			(at -0.939 -4.599 270)
			(layer "B.Fab")
			(effects
				(font
					(size 0.7 0.7)
					(thickness 0.15)
				)
				(justify left bottom mirror)
			)
		)
		(pad "1" smd roundrect
			(at -0.48 0 90)
			(size 0.59 0.64)
			(layers "B.Cu" "B.Mask" "B.Paste")
			(roundrect_rratio 0.25)
			(net 417 "GND")
			(pintype "passive")
		)
		(pad "2" smd roundrect
			(at 0.48 0 90)
			(size 0.59 0.64)
			(layers "B.Cu" "B.Mask" "B.Paste")
			(roundrect_rratio 0.25)
			(net 50 "+3V3")
			(pintype "passive")
		)
	)
	(footprint "antmicro-footprints:C_0402_1005Metric"
		(layer "B.Cu")
		(at 181.25 127)
		(descr "Capacitor SMD 0402")
		(tags "capacitor SMD 0402")
		(property "Reference" "C75"
			(at -0.91 1.4 0)
			(layer "B.SilkS")
			(effects
				(font
					(size 0.7 0.7)
					(thickness 0.15)
				)
				(justify right bottom mirror)
			)
		)
		(property "Value" "C_10u_0402"
			(at -1.022927 -2.155213 0)
			(layer "B.Fab")
			(hide yes)
			(effects
				(font
					(size 0.7 0.7)
					(thickness 0.15)
				)
				(justify right bottom mirror)
			)
		)
		(property "Datasheet" "https://www.yageo.com/en/Chart/Download/pdf/CC0402MRX5R5BB106"
			(at 0 0 0)
			(layer "F.Fab")
			(hide yes)
			(effects
				(font
					(size 1.27 1.27)
					(thickness 0.15)
				)
			)
		)
		(property "Description" "SMD Multilayer Ceramic Capacitor, 10 µF, 6.3 V, 0402 [1005 Metric], ± 20%, X5R, CC Series"
			(at 0 0 0)
			(layer "F.Fab")
			(hide yes)
			(effects
				(font
					(size 1.27 1.27)
					(thickness 0.15)
				)
			)
		)
		(property "Author" "Antmicro"
			(at 0 0 0)
			(layer "B.Fab")
			(hide yes)
			(effects
				(font
					(size 1 1)
					(thickness 0.15)
				)
				(justify mirror)
			)
		)
		(property "Dielectric" ""
			(at 0 0 0)
			(layer "B.Fab")
			(hide yes)
			(effects
				(font
					(size 1 1)
					(thickness 0.15)
				)
				(justify mirror)
			)
		)
		(property "License" "Apache-2.0"
			(at 0 0 0)
			(layer "B.Fab")
			(hide yes)
			(effects
				(font
					(size 1 1)
					(thickness 0.15)
				)
				(justify mirror)
			)
		)
		(property "MPN" "CC0402MRX5R5BB106"
			(at 0 0 0)
			(layer "B.Fab")
			(hide yes)
			(effects
				(font
					(size 1 1)
					(thickness 0.15)
				)
				(justify mirror)
			)
		)
		(property "Manufacturer" "YAGEO"
			(at 0 0 0)
			(layer "B.Fab")
			(hide yes)
			(effects
				(font
					(size 1 1)
					(thickness 0.15)
				)
				(justify mirror)
			)
		)
		(property "Public" ""
			(at 0 0 0)
			(layer "B.Fab")
			(hide yes)
			(effects
				(font
					(size 1 1)
					(thickness 0.15)
				)
				(justify mirror)
			)
		)
		(property "Val" "10u"
			(at 0 0 0)
			(layer "B.Fab")
			(hide yes)
			(effects
				(font
					(size 1 1)
					(thickness 0.15)
				)
				(justify mirror)
			)
		)
		(property "Voltage" ""
			(at 0 0 0)
			(layer "B.Fab")
			(hide yes)
			(effects
				(font
					(size 1 1)
					(thickness 0.15)
				)
				(justify mirror)
			)
		)
		(sheetname "/LPDDR4/")
		(sheetfile "lpddr.kicad_sch")
		(attr smd)
		(fp_rect
			(start -0.925 0.47)
			(end 0.925 -0.47)
			(stroke
				(width 0.05)
				(type default)
			)
			(fill no)
			(layer "B.CrtYd")
		)
		(fp_line
			(start -0.494 -0.248)
			(end -0.494 0.25)
			(stroke
				(width 0.15)
				(type solid)
			)
			(layer "B.Fab")
		)
		(fp_line
			(start -0.494 0.25)
			(end 0.504 0.25)
			(stroke
				(width 0.15)
				(type solid)
			)
			(layer "B.Fab")
		)
		(fp_line
			(start 0.504 -0.248)
			(end -0.494 -0.248)
			(stroke
				(width 0.15)
				(type solid)
			)
			(layer "B.Fab")
		)
		(fp_line
			(start 0.504 0.25)
			(end 0.504 -0.248)
			(stroke
				(width 0.15)
				(type solid)
			)
			(layer "B.Fab")
		)
		(fp_text user "${REFERENCE}"
			(at -0.939 -4.599 180)
			(layer "B.Fab")
			(effects
				(font
					(size 0.7 0.7)
					(thickness 0.15)
				)
				(justify left bottom mirror)
			)
		)
		(fp_text user "License: Apache-2.0"
			(at -0.939 -5.799 180)
			(layer "B.Fab")
			(effects
				(font
					(size 0.7 0.7)
					(thickness 0.15)
				)
				(justify left bottom mirror)
			)
		)
		(fp_text user "Author: Antmicro"
			(at -0.939 -3.399 180)
			(layer "B.Fab")
			(effects
				(font
					(size 0.7 0.7)
					(thickness 0.15)
				)
				(justify left bottom mirror)
			)
		)
		(pad "1" smd roundrect
			(at -0.48 0)
			(size 0.59 0.64)
			(layers "B.Cu" "B.Mask" "B.Paste")
			(roundrect_rratio 0.25)
			(net 417 "GND")
			(pintype "passive")
		)
		(pad "2" smd roundrect
			(at 0.48 0)
			(size 0.59 0.64)
			(layers "B.Cu" "B.Mask" "B.Paste")
			(roundrect_rratio 0.25)
			(net 48 "+1V8")
			(pintype "passive")
		)
	)
	(footprint "antmicro-footprints:R_0402_1005Metric"
		(layer "B.Cu")
		(at 224.38 133.275 180)
		(descr "Resistor SMD 0402")
		(tags "resistor SMD 0402")
		(property "Reference" "R45"
			(at -1.52 -1.325 0)
			(layer "B.SilkS")
			(effects
				(font
					(size 0.7 0.7)
					(thickness 0.15)
				)
				(justify left bottom mirror)
			)
		)
		(property "Value" "R_10k_0402"
			(at -1.011843 -1.772047 0)
			(layer "B.Fab")
			(hide yes)
			(effects
				(font
					(size 0.7 0.7)
					(thickness 0.15)
				)
				(justify left bottom mirror)
			)
		)
		(property "Datasheet" "https://www.bourns.com/docs/product-datasheets/cr.pdf"
			(at 0 0 180)
			(layer "F.Fab")
			(hide yes)
			(effects
				(font
					(size 1.27 1.27)
					(thickness 0.15)
				)
			)
		)
		(property "Description" "SMD Chip Resistor, 10 kohm, ± 1%, 62.5 mW, 0402 [1005 Metric], Thick Film, General Purpose"
			(at 0 0 180)
			(layer "F.Fab")
			(hide yes)
			(effects
				(font
					(size 1.27 1.27)
					(thickness 0.15)
				)
			)
		)
		(property "Author" "Antmicro"
			(at 448.76 266.55 0)
			(layer "B.Fab")
			(hide yes)
			(effects
				(font
					(size 1 1)
					(thickness 0.15)
				)
				(justify mirror)
			)
		)
		(property "License" "Apache-2.0"
			(at 448.76 266.55 0)
			(layer "B.Fab")
			(hide yes)
			(effects
				(font
					(size 1 1)
					(thickness 0.15)
				)
				(justify mirror)
			)
		)
		(property "MPN" "CR0402-FX-1002GLF"
			(at 448.76 266.55 0)
			(layer "B.Fab")
			(hide yes)
			(effects
				(font
					(size 1 1)
					(thickness 0.15)
				)
				(justify mirror)
			)
		)
		(property "Manufacturer" "Bourns"
			(at 448.76 266.55 0)
			(layer "B.Fab")
			(hide yes)
			(effects
				(font
					(size 1 1)
					(thickness 0.15)
				)
				(justify mirror)
			)
		)
		(property "Public" ""
			(at 448.76 266.55 0)
			(layer "B.Fab")
			(hide yes)
			(effects
				(font
					(size 1 1)
					(thickness 0.15)
				)
				(justify mirror)
			)
		)
		(property "Tolerance" "1%"
			(at 448.76 266.55 0)
			(layer "B.Fab")
			(hide yes)
			(effects
				(font
					(size 1 1)
					(thickness 0.15)
				)
				(justify mirror)
			)
		)
		(property "Val" "10k"
			(at 448.76 266.55 0)
			(layer "B.Fab")
			(hide yes)
			(effects
				(font
					(size 1 1)
					(thickness 0.15)
				)
				(justify mirror)
			)
		)
		(sheetname "/FPGA Config/")
		(sheetfile "fpga-config.kicad_sch")
		(attr smd)
		(fp_rect
			(start -0.925 0.47)
			(end 0.925 -0.47)
			(stroke
				(width 0.05)
				(type default)
			)
			(fill no)
			(layer "B.CrtYd")
		)
		(fp_rect
			(start -0.5 0.25)
			(end 0.5 -0.25)
			(stroke
				(width 0.15)
				(type solid)
			)
			(fill no)
			(layer "B.Fab")
		)
		(fp_text user "License: Apache-2.0"
			(at -0.95 -5.169 0)
			(layer "B.Fab")
			(effects
				(font
					(size 0.7 0.7)
					(thickness 0.15)
				)
				(justify left bottom mirror)
			)
		)
		(fp_text user "${REFERENCE}"
			(at -0.95 -3.168 0)
			(layer "B.Fab")
			(effects
				(font
					(size 0.7 0.7)
					(thickness 0.15)
				)
				(justify left bottom mirror)
			)
		)
		(fp_text user "Author: Antmicro"
			(at -0.95 -4.169 0)
			(layer "B.Fab")
			(effects
				(font
					(size 0.7 0.7)
					(thickness 0.15)
				)
				(justify left bottom mirror)
			)
		)
		(pad "1" smd roundrect
			(at -0.48 0 180)
			(size 0.59 0.64)
			(layers "B.Cu" "B.Mask" "B.Paste")
			(roundrect_rratio 0.25)
			(net 258 "Net-(U3-W#{slash}DQ2)")
			(pintype "passive")
		)
		(pad "2" smd roundrect
			(at 0.48 0 180)
			(size 0.59 0.64)
			(layers "B.Cu" "B.Mask" "B.Paste")
			(roundrect_rratio 0.25)
			(net 50 "+3V3")
			(pintype "passive")
		)
	)
	(footprint "antmicro-footprints:C_0402_1005Metric"
		(layer "B.Cu")
		(at 217.98 141.56 90)
		(descr "Capacitor SMD 0402")
		(tags "capacitor SMD 0402")
		(property "Reference" "C123"
			(at 1.29 -0.33 180)
			(layer "B.SilkS")
			(effects
				(font
					(size 0.7 0.7)
					(thickness 0.15)
				)
				(justify right bottom mirror)
			)
		)
		(property "Value" "C_100n_0402"
			(at -1.022927 -2.155213 90)
			(layer "B.Fab")
			(hide yes)
			(effects
				(font
					(size 0.7 0.7)
					(thickness 0.15)
				)
				(justify right bottom mirror)
			)
		)
		(property "Datasheet" "https://www.murata.com/products/productdetail?partno=GRM155R61H104KE14%23"
			(at 0 0 90)
			(layer "F.Fab")
			(hide yes)
			(effects
				(font
					(size 1.27 1.27)
					(thickness 0.15)
				)
			)
		)
		(property "Description" "SMD Multilayer Ceramic Capacitor, 0.1 µF, 50 V, 0402 [1005 Metric], ± 10%, X5R, GRM Series"
			(at 0 0 90)
			(layer "F.Fab")
			(hide yes)
			(effects
				(font
					(size 1.27 1.27)
					(thickness 0.15)
				)
			)
		)
		(property "Author" "Antmicro"
			(at 359.54 -76.42 0)
			(layer "B.Fab")
			(hide yes)
			(effects
				(font
					(size 1 1)
					(thickness 0.15)
				)
				(justify mirror)
			)
		)
		(property "Dielectric" "X5R"
			(at 359.54 -76.42 0)
			(layer "B.Fab")
			(hide yes)
			(effects
				(font
					(size 1 1)
					(thickness 0.15)
				)
				(justify mirror)
			)
		)
		(property "License" "Apache-2.0"
			(at 359.54 -76.42 0)
			(layer "B.Fab")
			(hide yes)
			(effects
				(font
					(size 1 1)
					(thickness 0.15)
				)
				(justify mirror)
			)
		)
		(property "MPN" "GRM155R61H104KE14D"
			(at 359.54 -76.42 0)
			(layer "B.Fab")
			(hide yes)
			(effects
				(font
					(size 1 1)
					(thickness 0.15)
				)
				(justify mirror)
			)
		)
		(property "Manufacturer" "Murata"
			(at 359.54 -76.42 0)
			(layer "B.Fab")
			(hide yes)
			(effects
				(font
					(size 1 1)
					(thickness 0.15)
				)
				(justify mirror)
			)
		)
		(property "Public" ""
			(at 359.54 -76.42 0)
			(layer "B.Fab")
			(hide yes)
			(effects
				(font
					(size 1 1)
					(thickness 0.15)
				)
				(justify mirror)
			)
		)
		(property "Val" "100n"
			(at 359.54 -76.42 0)
			(layer "B.Fab")
			(hide yes)
			(effects
				(font
					(size 1 1)
					(thickness 0.15)
				)
				(justify mirror)
			)
		)
		(property "Voltage" "50V"
			(at 359.54 -76.42 0)
			(layer "B.Fab")
			(hide yes)
			(effects
				(font
					(size 1 1)
					(thickness 0.15)
				)
				(justify mirror)
			)
		)
		(sheetname "/FPGA GPIO/")
		(sheetfile "fpga-gpio.kicad_sch")
		(attr smd)
		(fp_rect
			(start -0.925 0.47)
			(end 0.925 -0.47)
			(stroke
				(width 0.05)
				(type default)
			)
			(fill no)
			(layer "B.CrtYd")
		)
		(fp_line
			(start 0.504 -0.248)
			(end -0.494 -0.248)
			(stroke
				(width 0.15)
				(type solid)
			)
			(layer "B.Fab")
		)
		(fp_line
			(start -0.494 -0.248)
			(end -0.494 0.25)
			(stroke
				(width 0.15)
				(type solid)
			)
			(layer "B.Fab")
		)
		(fp_line
			(start 0.504 0.25)
			(end 0.504 -0.248)
			(stroke
				(width 0.15)
				(type solid)
			)
			(layer "B.Fab")
		)
		(fp_line
			(start -0.494 0.25)
			(end 0.504 0.25)
			(stroke
				(width 0.15)
				(type solid)
			)
			(layer "B.Fab")
		)
		(fp_text user "${REFERENCE}"
			(at -0.939 -4.599 270)
			(layer "B.Fab")
			(effects
				(font
					(size 0.7 0.7)
					(thickness 0.15)
				)
				(justify left bottom mirror)
			)
		)
		(fp_text user "License: Apache-2.0"
			(at -0.939 -5.799 270)
			(layer "B.Fab")
			(effects
				(font
					(size 0.7 0.7)
					(thickness 0.15)
				)
				(justify left bottom mirror)
			)
		)
		(fp_text user "Author: Antmicro"
			(at -0.939 -3.399 270)
			(layer "B.Fab")
			(effects
				(font
					(size 0.7 0.7)
					(thickness 0.15)
				)
				(justify left bottom mirror)
			)
		)
		(pad "1" smd roundrect
			(at -0.48 0 90)
			(size 0.59 0.64)
			(layers "B.Cu" "B.Mask" "B.Paste")
			(roundrect_rratio 0.25)
			(net 649 "VDD")
			(pintype "passive")
		)
		(pad "2" smd roundrect
			(at 0.48 0 90)
			(size 0.59 0.64)
			(layers "B.Cu" "B.Mask" "B.Paste")
			(roundrect_rratio 0.25)
			(net 417 "GND")
			(pintype "passive")
		)
	)
)
